(kicad_pcb
	(version 20260206)
	(generator "pcbnew")
	(generator_version "10.0")
	(general
		(thickness 1.6)
		(legacy_teardrops no)
	)
	(paper "A4")
	(title_block
		(title "ptb — 12523-1.1018WZS1506.brd")
		(comment 1 "Open Vault / Knox (Wiwynn) / footprints 12-17 of 61")
	)
	(layers
		(0 "F.Cu" signal "TOP")
		(4 "In1.Cu" signal "L2GND")
		(6 "In2.Cu" signal "L3VCC")
		(2 "B.Cu" signal "BOTTOM")
		(9 "F.Adhes" user "F.Adhesive")
		(11 "B.Adhes" user "B.Adhesive")
		(13 "F.Paste" user "Package Geometry/Pastemask Top")
		(15 "B.Paste" user "Package Geometry/Pastemask Bottom")
		(5 "F.SilkS" user "Ref Des/Silkscreen Top")
		(7 "B.SilkS" user "Ref Des/Silkscreen Bottom")
		(1 "F.Mask" user "Board Geometry/Soldermask Top")
		(3 "B.Mask" user "Board Geometry/Soldermask Bottom")
		(17 "Dwgs.User" user "User.Drawings")
		(19 "Cmts.User" user "User.Comments")
		(21 "Eco1.User" user "User.Eco1")
		(23 "Eco2.User" user "User.Eco2")
		(25 "Edge.Cuts" user "Board Geometry/Outline")
		(27 "Margin" user)
		(31 "F.CrtYd" user "Package Geometry/Place Bound Top")
		(29 "B.CrtYd" user "Package Geometry/Place Bound Bottom")
		(35 "F.Fab" user "Ref Des/Assembly Top")
		(33 "B.Fab" user "Ref Des/Assembly Bottom")
	)
	(footprint ""
		(layer "F.Cu")
		(at 152.15997 -18.999962 -90)
		(property "Reference" "SW1"
			(at 0 0 270)
			(layer "F.SilkS")
			(hide yes)
			(effects
				(font
					(size 1.27 1.27)
				)
			)
		)
		(property "Value" "SW-SLIDE3P-15-GP"
			(at -6.498844 1.074928 270)
			(unlocked yes)
			(layer "F.Fab")
			(hide yes)
			(effects
				(font
					(size 1.016 1.016)
					(thickness 0.1524)
				)
			)
		)
		(property "Device Type" "SSS-1206"
			(at -6.498844 -0.449072 270)
			(unlocked yes)
			(layer "F.Fab")
			(hide yes)
			(effects
				(font
					(size 1.016 1.016)
					(thickness 0.1524)
				)
			)
		)
		(duplicate_pad_numbers_are_jumpers no)
		(fp_line
			(start -5.2578 1.7526)
			(end -5.2578 -1.7526)
			(stroke
				(width 0.1524)
				(type default)
			)
			(layer "F.SilkS")
		)
		(fp_line
			(start 5.2578 1.7526)
			(end -5.2578 1.7526)
			(stroke
				(width 0.1524)
				(type default)
			)
			(layer "F.SilkS")
		)
		(fp_line
			(start -5.2578 -1.7526)
			(end 5.2578 -1.7526)
			(stroke
				(width 0.1524)
				(type default)
			)
			(layer "F.SilkS")
		)
		(fp_line
			(start 5.2578 -1.7526)
			(end 5.2578 1.7526)
			(stroke
				(width 0.1524)
				(type default)
			)
			(layer "F.SilkS")
		)
		(fp_circle
			(center -1.999996 0.750062)
			(end -1.999996 -0.278638)
			(stroke
				(width 0.3048)
				(type default)
			)
			(fill no)
			(layer "F.SilkS")
		)
		(fp_circle
			(center 1.999996 0.750062)
			(end 1.999996 -0.278638)
			(stroke
				(width 0.3048)
				(type default)
			)
			(fill no)
			(layer "F.SilkS")
		)
		(fp_circle
			(center 0 -0.750062)
			(end 0 -1.778762)
			(stroke
				(width 0.3048)
				(type default)
			)
			(fill no)
			(layer "F.SilkS")
		)
		(fp_rect
			(start -5.0038 1.4986)
			(end 5.0038 -1.4986)
			(stroke
				(width 0)
				(type default)
			)
			(fill no)
			(layer "F.CrtYd")
		)
		(fp_poly
			(pts
				(xy -5.5118 2.0066) (xy -5.5118 -2.0066) (xy 5.5118 -2.0066) (xy 5.5118 -0.00635) (xy 5.0038 -0.00635)
				(xy 5.0038 -1.4986) (xy -5.0038 -1.4986) (xy -5.0038 1.4986) (xy 5.0038 1.4986) (xy 5.0038 0.00635)
				(xy 5.5118 0.00635) (xy 5.5118 2.0066)
			)
			(stroke
				(width 0)
				(type default)
			)
			(fill no)
			(layer "F.CrtYd")
		)
		(fp_rect
			(start -5.5118 2.0066)
			(end 5.5118 -2.0066)
			(stroke
				(width 0)
				(type default)
			)
			(fill no)
			(layer "F.Fab")
		)
		(pad "" np_thru_hole circle
			(at -3.999992 0 270)
			(size 0.254 0.254)
			(drill 0.8636)
			(layers "*.Cu" "*.Mask")
			(clearance 0.6604)
			(thermal_gap 0.6604)
		)
		(pad "" np_thru_hole circle
			(at 3.999992 0 270)
			(size 0.254 0.254)
			(drill 0.8636)
			(layers "*.Cu" "*.Mask")
			(clearance 0.6604)
			(thermal_gap 0.6604)
		)
		(pad "1" thru_hole circle
			(at -1.999996 0.750062 270)
			(size 1.3462 1.3462)
			(drill 0.9398)
			(layers "*.Cu" "*.Mask")
			(remove_unused_layers no)
			(net "TPS2490_EN1")
			(clearance 0.1524)
			(thermal_gap 0.1524)
		)
		(pad "2" thru_hole circle
			(at 0 -0.750062 270)
			(size 1.3462 1.3462)
			(drill 0.9398)
			(layers "*.Cu" "*.Mask")
			(remove_unused_layers no)
			(net "TPS2490_EN2")
			(clearance 0.1524)
			(thermal_gap 0.1524)
		)
		(pad "3" thru_hole circle
			(at 1.999996 0.750062 270)
			(size 1.3462 1.3462)
			(drill 0.9398)
			(layers "*.Cu" "*.Mask")
			(remove_unused_layers no)
			(net "TPS2490_DISABLE")
			(clearance 0.1524)
			(thermal_gap 0.1524)
		)
		(zone
			(layers "F.Cu" "B.Cu" "In1.Cu" "In2.Cu")
			(hatch none 0.5)
			(connect_pads
				(clearance 0)
			)
			(min_thickness 0.25)
			(keepout
				(tracks not_allowed)
				(vias allowed)
				(pads allowed)
				(copperpour not_allowed)
				(footprints allowed)
			)
			(placement
				(enabled no)
				(sheetname "")
			)
			(fill
				(thermal_gap 0.5)
				(thermal_bridge_width 0.5)
				(island_removal_mode 0)
			)
			(polygon
				(pts
					(arc
						(start 152.15997 -22.263354)
						(mid 152.15997 -23.736554)
						(end 152.15997 -22.263354)
					)
				)
			)
		)
		(zone
			(layers "F.Cu" "B.Cu" "In1.Cu" "In2.Cu")
			(hatch none 0.5)
			(connect_pads
				(clearance 0)
			)
			(min_thickness 0.25)
			(keepout
				(tracks not_allowed)
				(vias allowed)
				(pads allowed)
				(copperpour not_allowed)
				(footprints allowed)
			)
			(placement
				(enabled no)
				(sheetname "")
			)
			(fill
				(thermal_gap 0.5)
				(thermal_bridge_width 0.5)
				(island_removal_mode 0)
			)
			(polygon
				(pts
					(arc
						(start 152.15997 -14.26337)
						(mid 152.15997 -15.73657)
						(end 152.15997 -14.26337)
					)
				)
			)
		)
	)
	(footprint ""
		(layer "F.Cu")
		(at 123.85675 -47.164244 180)
		(property "Reference" "TC3"
			(at 0 0 180)
			(layer "F.SilkS")
			(hide yes)
			(effects
				(font
					(size 1.27 1.27)
				)
			)
		)
		(property "Value" "ST68U16VDM-1-GP"
			(at 0 -9.6012 180)
			(unlocked yes)
			(layer "F.Fab")
			(hide yes)
			(effects
				(font
					(size 1.016 1.016)
					(thickness 0.1524)
				)
			)
		)
		(property "Device Type" "CT7343H79"
			(at 0 -11.1252 180)
			(unlocked yes)
			(layer "F.Fab")
			(hide yes)
			(effects
				(font
					(size 1.016 1.016)
					(thickness 0.1524)
				)
			)
		)
		(duplicate_pad_numbers_are_jumpers no)
		(fp_line
			(start 2.286 4.8768)
			(end -2.286 4.8768)
			(stroke
				(width 0.1524)
				(type default)
			)
			(layer "F.SilkS")
		)
		(fp_line
			(start 2.286 2.032)
			(end 2.286 4.8768)
			(stroke
				(width 0.1524)
				(type default)
			)
			(layer "F.SilkS")
		)
		(fp_line
			(start 2.286 -2.032)
			(end 2.286 -4.8768)
			(stroke
				(width 0.1524)
				(type default)
			)
			(layer "F.SilkS")
		)
		(fp_line
			(start 2.286 -4.8768)
			(end -2.286 -4.8768)
			(stroke
				(width 0.1524)
				(type default)
			)
			(layer "F.SilkS")
		)
		(fp_line
			(start 2.1082 -4.699)
			(end -2.1082 -4.699)
			(stroke
				(width 0.508)
				(type default)
			)
			(layer "F.SilkS")
		)
		(fp_line
			(start -2.286 4.8768)
			(end -2.286 2.032)
			(stroke
				(width 0.1524)
				(type default)
			)
			(layer "F.SilkS")
		)
		(fp_line
			(start -2.286 -4.8768)
			(end -2.286 -2.032)
			(stroke
				(width 0.1524)
				(type default)
			)
			(layer "F.SilkS")
		)
		(fp_rect
			(start -2.1463 3.6449)
			(end 2.1463 -3.6449)
			(stroke
				(width 0)
				(type default)
			)
			(fill no)
			(layer "F.CrtYd")
		)
		(fp_poly
			(pts
				(xy -2.54 4.953) (xy -2.54 4.2926) (xy -3.81 4.2926) (xy -3.81 -4.2926) (xy -2.54 -4.2926) (xy -2.54 -4.953)
				(xy 2.54 -4.953) (xy 2.54 -4.2926) (xy 3.81 -4.2926) (xy 3.81 -1.6256) (xy 2.1463 -1.6256) (xy 2.1463 -3.6449)
				(xy -2.1463 -3.6449) (xy -2.1463 3.6449) (xy 2.1463 3.6449) (xy 2.1463 -1.6129) (xy 3.81 -1.6129)
				(xy 3.81 4.2926) (xy 2.54 4.2926) (xy 2.54 4.953)
			)
			(stroke
				(width 0)
				(type default)
			)
			(fill no)
			(layer "F.CrtYd")
		)
		(fp_rect
			(start 2.54 4.2926)
			(end 3.81 -4.2926)
			(stroke
				(width 0)
				(type default)
			)
			(fill no)
			(layer "F.Fab")
		)
		(fp_rect
			(start -2.54 4.953)
			(end 2.54 -4.953)
			(stroke
				(width 0)
				(type default)
			)
			(fill no)
			(layer "F.Fab")
		)
		(fp_rect
			(start -3.81 4.2926)
			(end -2.54 -4.2926)
			(stroke
				(width 0)
				(type default)
			)
			(fill no)
			(layer "F.Fab")
		)
		(pad "1" smd rect
			(at 0 -3.1496 180)
			(size 2.413 2.286)
			(layers "F.Cu" "F.Mask" "F.Paste")
			(net "P12V")
		)
		(pad "2" smd rect
			(at 0 3.1496 180)
			(size 2.413 2.286)
			(layers "F.Cu" "F.Mask" "F.Paste")
			(net "GND")
		)
		(zone
			(layer "F.Cu")
			(hatch none 0.5)
			(connect_pads
				(clearance 0)
			)
			(min_thickness 0.25)
			(keepout
				(tracks allowed)
				(vias not_allowed)
				(pads allowed)
				(copperpour not_allowed)
				(footprints allowed)
			)
			(placement
				(enabled no)
				(sheetname "")
			)
			(fill
				(thermal_gap 0.5)
				(thermal_bridge_width 0.5)
				(island_removal_mode 0)
			)
			(polygon
				(pts
					(xy 122.34545 -45.475144) (xy 122.34545 -42.566844) (xy 125.36805 -42.566844) (xy 125.36805 -45.462444)
					(xy 125.36805 -45.792644) (xy 122.34545 -45.792644)
				)
			)
		)
		(zone
			(layer "F.Cu")
			(hatch none 0.5)
			(connect_pads
				(clearance 0)
			)
			(min_thickness 0.25)
			(keepout
				(tracks allowed)
				(vias not_allowed)
				(pads allowed)
				(copperpour not_allowed)
				(footprints allowed)
			)
			(placement
				(enabled no)
				(sheetname "")
			)
			(fill
				(thermal_gap 0.5)
				(thermal_bridge_width 0.5)
				(island_removal_mode 0)
			)
			(polygon
				(pts
					(xy 125.36805 -51.761644) (xy 122.34545 -51.761644) (xy 122.34545 -48.866044) (xy 122.34545 -48.535844)
					(xy 125.36805 -48.535844) (xy 125.36805 -48.866044)
				)
			)
		)
	)
	(footprint ""
		(layer "F.Cu")
		(at 137.795 -69.080634 180)
		(property "Reference" "C360"
			(at 0 0 180)
			(layer "F.SilkS")
			(hide yes)
			(effects
				(font
					(size 1.27 1.27)
				)
			)
		)
		(property "Value" "SC220P50V3JN-GP"
			(at 0 -2.8194 180)
			(unlocked yes)
			(layer "F.Fab")
			(hide yes)
			(effects
				(font
					(size 1.016 1.016)
					(thickness 0.1524)
				)
			)
		)
		(property "Device Type" "C603H36"
			(at 0 -4.3434 180)
			(unlocked yes)
			(layer "F.Fab")
			(hide yes)
			(effects
				(font
					(size 1.016 1.016)
					(thickness 0.1524)
				)
			)
		)
		(duplicate_pad_numbers_are_jumpers no)
		(fp_line
			(start 0.508 0)
			(end -0.508 0)
			(stroke
				(width 0.2032)
				(type default)
			)
			(layer "F.SilkS")
		)
		(fp_rect
			(start -0.5842 1.3335)
			(end 0.5842 -1.3335)
			(stroke
				(width 0)
				(type default)
			)
			(fill no)
			(layer "F.CrtYd")
		)
		(fp_rect
			(start -0.5842 1.3335)
			(end 0.5842 -1.3335)
			(stroke
				(width 0)
				(type default)
			)
			(fill no)
			(layer "F.Fab")
		)
		(pad "1" smd custom
			(at 0 -0.762 180)
			(size 0.2159 0.2159)
			(layers "F.Cu" "F.Mask" "F.Paste")
			(net "I2C_C_BUF_SDA_CONN")
			(options
				(clearance outline)
				(anchor circle)
			)
			(primitives
				(gr_poly
					(pts
						(arc
							(start -0.3302 -0.4318)
							(mid -0.402042 -0.402042)
							(end -0.4318 -0.3302)
						)
						(arc
							(start -0.4318 0.3302)
							(mid -0.402042 0.402042)
							(end -0.3302 0.4318)
						)
						(arc
							(start 0.3302 0.4318)
							(mid 0.402042 0.402042)
							(end 0.4318 0.3302)
						)
						(arc
							(start 0.4318 -0.3302)
							(mid 0.402042 -0.402042)
							(end 0.3302 -0.4318)
						)
					)
					(width 0)
					(fill yes)
				)
			)
		)
		(pad "2" smd custom
			(at 0 0.762 180)
			(size 0.2159 0.2159)
			(layers "F.Cu" "F.Mask" "F.Paste")
			(net "GND")
			(options
				(clearance outline)
				(anchor circle)
			)
			(primitives
				(gr_poly
					(pts
						(arc
							(start -0.3302 -0.4318)
							(mid -0.402042 -0.402042)
							(end -0.4318 -0.3302)
						)
						(arc
							(start -0.4318 0.3302)
							(mid -0.402042 0.402042)
							(end -0.3302 0.4318)
						)
						(arc
							(start 0.3302 0.4318)
							(mid 0.402042 0.402042)
							(end 0.4318 0.3302)
						)
						(arc
							(start 0.4318 -0.3302)
							(mid 0.402042 -0.402042)
							(end 0.3302 -0.4318)
						)
					)
					(width 0)
					(fill yes)
				)
			)
		)
	)
	(footprint ""
		(layer "F.Cu")
		(at 14.579092 -89.95664 180)
		(property "Reference" "R369"
			(at 0 0 180)
			(layer "F.SilkS")
			(hide yes)
			(effects
				(font
					(size 1.27 1.27)
				)
			)
		)
		(property "Value" "4K7R2J-2-GP"
			(at 0.064008 -3.993896 180)
			(unlocked yes)
			(layer "F.Fab")
			(hide yes)
			(effects
				(font
					(size 1.016 1.016)
					(thickness 0.1524)
				)
			)
		)
		(property "Device Type" "R402H16"
			(at 0.064008 -5.517896 180)
			(unlocked yes)
			(layer "F.Fab")
			(hide yes)
			(effects
				(font
					(size 1.016 1.016)
					(thickness 0.1524)
				)
			)
		)
		(duplicate_pad_numbers_are_jumpers no)
		(fp_line
			(start 0.508 -0.9398)
			(end -0.508 -0.9398)
			(stroke
				(width 0.1524)
				(type default)
			)
			(layer "F.SilkS")
		)
		(fp_line
			(start -0.508 -0.9398)
			(end -0.508 0.9398)
			(stroke
				(width 0.1524)
				(type default)
			)
			(layer "F.SilkS")
		)
		(fp_rect
			(start -0.508 0.9398)
			(end 0.508 -0.9398)
			(stroke
				(width 0)
				(type default)
			)
			(fill no)
			(layer "F.CrtYd")
		)
		(fp_rect
			(start -0.508 0.9398)
			(end 0.508 -0.9398)
			(stroke
				(width 0)
				(type default)
			)
			(fill no)
			(layer "F.Fab")
		)
		(pad "1" smd custom
			(at 0 -0.4445 180)
			(size 0.1397 0.1397)
			(layers "F.Cu" "F.Mask" "F.Paste")
			(net "P3V3")
			(options
				(clearance outline)
				(anchor circle)
			)
			(primitives
				(gr_poly
					(pts
						(arc
							(start -0.1778 -0.2794)
							(mid -0.249642 -0.249642)
							(end -0.2794 -0.1778)
						)
						(arc
							(start -0.2794 0.1778)
							(mid -0.249642 0.249642)
							(end -0.1778 0.2794)
						)
						(arc
							(start 0.1778 0.2794)
							(mid 0.249642 0.249642)
							(end 0.2794 0.1778)
						)
						(arc
							(start 0.2794 -0.1778)
							(mid 0.249642 -0.249642)
							(end 0.1778 -0.2794)
						)
					)
					(width 0)
					(fill yes)
				)
			)
		)
		(pad "2" smd custom
			(at 0 0.4445 180)
			(size 0.1397 0.1397)
			(layers "F.Cu" "F.Mask" "F.Paste")
			(net "I2C_C_BUF_SCLIN")
			(options
				(clearance outline)
				(anchor circle)
			)
			(primitives
				(gr_poly
					(pts
						(arc
							(start -0.1778 -0.2794)
							(mid -0.249642 -0.249642)
							(end -0.2794 -0.1778)
						)
						(arc
							(start -0.2794 0.1778)
							(mid -0.249642 0.249642)
							(end -0.1778 0.2794)
						)
						(arc
							(start 0.1778 0.2794)
							(mid 0.249642 0.249642)
							(end 0.2794 0.1778)
						)
						(arc
							(start 0.2794 -0.1778)
							(mid 0.249642 -0.249642)
							(end 0.1778 -0.2794)
						)
					)
					(width 0)
					(fill yes)
				)
			)
		)
	)
	(footprint ""
		(layer "F.Cu")
		(at 149.659848 -113.999772)
		(property "Reference" "H1"
			(at 0 0 0)
			(layer "F.SilkS")
			(hide yes)
			(effects
				(font
					(size 1.27 1.27)
				)
			)
		)
		(property "Value" "HOLET827X355B355R158-S"
			(at -18.200878 0.089916 0)
			(unlocked yes)
			(layer "F.Fab")
			(hide yes)
			(effects
				(font
					(size 1.016 1.016)
					(thickness 0.1524)
				)
			)
		)
		(property "Device Type" "HOLET827X355B355R158-S"
			(at -18.200878 -1.434084 0)
			(unlocked yes)
			(layer "F.Fab")
			(hide yes)
			(effects
				(font
					(size 1.016 1.016)
					(thickness 0.1524)
				)
			)
		)
		(duplicate_pad_numbers_are_jumpers no)
		(fp_poly
			(pts
				(arc
					(start -4.8133 0)
					(mid 4.8133 0)
					(end -4.8133 0)
				)
			)
			(stroke
				(width 0)
				(type default)
			)
			(fill no)
			(layer "B.CrtYd")
		)
		(fp_poly
			(pts
				(arc
					(start -11.9888 4.8133)
					(mid -16.8021 0)
					(end -11.9888 -4.8133)
				)
				(arc
					(start 0 -4.8133)
					(mid 4.8133 0)
					(end 0 4.8133)
				)
			)
			(stroke
				(width 0)
				(type default)
			)
			(fill no)
			(layer "F.CrtYd")
		)
		(fp_poly
			(pts
				(arc
					(start -4.8133 0)
					(mid 4.8133 0)
					(end -4.8133 0)
				)
			)
			(stroke
				(width 0)
				(type default)
			)
			(fill no)
			(layer "B.Fab")
		)
		(fp_poly
			(pts
				(arc
					(start -11.9888 4.8133)
					(mid -16.8021 0)
					(end -11.9888 -4.8133)
				)
				(arc
					(start 0 -4.8133)
					(mid 4.8133 0)
					(end 0 4.8133)
				)
			)
			(stroke
				(width 0)
				(type default)
			)
			(fill no)
			(layer "F.Fab")
		)
		(pad "1" thru_hole oval
			(at 0 0)
			(size 21.0058 9.017)
			(drill 4.0132
				(offset -5.9944 0)
			)
			(layers "*.Cu" "*.Mask")
			(remove_unused_layers no)
			(net "GND")
			(clearance -7.9883)
			(thermal_gap 0.3048)
			(padstack
				(mode front_inner_back)
				(layer "Inner"
					(shape circle)
					(size 4.4196 4.4196)
					(clearance 0.3048)
				)
				(layer "B.Cu"
					(shape circle)
					(size 9.017 9.017)
					(clearance -1.9939)
				)
			)
		)
	)
	(footprint ""
		(layer "F.Cu")
		(at 2.361438 -49.179226 180)
		(property "Reference" "C349"
			(at 0 0 180)
			(layer "F.SilkS")
			(hide yes)
			(effects
				(font
					(size 1.27 1.27)
				)
			)
		)
		(property "Value" "SC10U25V5KX-GP"
			(at -0.0762 -6.1214 180)
			(unlocked yes)
			(layer "F.Fab")
			(hide yes)
			(effects
				(font
					(size 1.016 1.016)
					(thickness 0.1524)
				)
			)
		)
		(property "Device Type" "C805H56"
			(at -0.0762 -8.1534 180)
			(unlocked yes)
			(layer "F.Fab")
			(hide yes)
			(effects
				(font
					(size 1.016 1.016)
					(thickness 0.1524)
				)
			)
		)
		(duplicate_pad_numbers_are_jumpers no)
		(fp_line
			(start 0.635 0)
			(end -0.635 0)
			(stroke
				(width 0.508)
				(type default)
			)
			(layer "F.SilkS")
		)
		(fp_rect
			(start -0.9652 1.778)
			(end 0.9652 -1.778)
			(stroke
				(width 0)
				(type default)
			)
			(fill no)
			(layer "F.CrtYd")
		)
		(fp_poly
			(pts
				(xy -0.9652 -1.778) (xy 0.9652 -1.778) (xy 0.9652 1.778) (xy -0.9652 1.778)
			)
			(stroke
				(width 0)
				(type default)
			)
			(fill no)
			(layer "F.Fab")
		)
		(pad "1" smd rect
			(at 0 -0.9652 180)
			(size 1.397 1.143)
			(layers "F.Cu" "F.Mask" "F.Paste")
			(net "P12V")
		)
		(pad "2" smd rect
			(at 0 0.9652 180)
			(size 1.397 1.143)
			(layers "F.Cu" "F.Mask" "F.Paste")
			(net "GND")
		)
	)
)
